(kicad_pcb
	(version 20260206)
	(generator "pcbnew")
	(generator_version "10.0")
	(general
		(thickness 1.6)
		(legacy_teardrops no)
	)
	(paper "A4")
	(title_block
		(title "01162023_DA0F0TEBIF0_F0T_Expander_BD_F_brd_V02_OCP.brd")
		(comment 1 "Grand Teton / footprints 5673-5678 of 9728")
	)
	(layers
		(0 "F.Cu" signal "TOP")
		(4 "In1.Cu" signal "GND")
		(6 "In2.Cu" signal "VCC")
		(8 "In3.Cu" signal "VCC1")
		(10 "In4.Cu" signal "GND1")
		(12 "In5.Cu" signal "IN1")
		(14 "In6.Cu" signal "GND2")
		(16 "In7.Cu" signal "IN2")
		(18 "In8.Cu" signal "GND3")
		(20 "In9.Cu" signal "IN3")
		(22 "In10.Cu" signal "GND4")
		(24 "In11.Cu" signal "IN4")
		(26 "In12.Cu" signal "GND5")
		(28 "In13.Cu" signal "IN5")
		(30 "In14.Cu" signal "GND6")
		(32 "In15.Cu" signal "IN6")
		(34 "In16.Cu" signal "GND7")
		(2 "B.Cu" signal "BOTTOM")
		(9 "F.Adhes" user "F.Adhesive")
		(11 "B.Adhes" user "B.Adhesive")
		(13 "F.Paste" user "Package Geometry/Pastemask Top")
		(15 "B.Paste" user "Package Geometry/Pastemask Bottom")
		(5 "F.SilkS" user "Ref Des/Silkscreen Top")
		(7 "B.SilkS" user "Ref Des/Silkscreen Bottom")
		(1 "F.Mask" user "Board Geometry/Soldermask Top")
		(3 "B.Mask" user "Board Geometry/Soldermask Bottom")
		(17 "Dwgs.User" user "User.Drawings")
		(19 "Cmts.User" user "User.Comments")
		(21 "Eco1.User" user "User.Eco1")
		(23 "Eco2.User" user "User.Eco2")
		(25 "Edge.Cuts" user "Board Geometry/Outline")
		(27 "Margin" user)
		(31 "F.CrtYd" user "Package Geometry/Place Bound Top")
		(29 "B.CrtYd" user "Package Geometry/Place Bound Bottom")
		(35 "F.Fab" user "Ref Des/Assembly Top")
		(33 "B.Fab" user "Ref Des/Assembly Bottom")
	)
	(footprint ""
		(layer "F.Cu")
		(at 35.518344 -250.070874 -90)
		(property "Reference" "R1166"
			(at 0 0 270)
			(layer "F.SilkS")
			(hide yes)
			(effects
				(font
					(size 1.27 1.27)
				)
			)
		)
		(property "Value" ""
			(at 0 0 270)
			(layer "F.Fab")
			(effects
				(font
					(size 1.27 1.27)
				)
			)
		)
		(duplicate_pad_numbers_are_jumpers no)
		(fp_line
			(start -0.7874 0.4064)
			(end -0.7874 -0.4064)
			(stroke
				(width 0.1524)
				(type default)
			)
			(layer "F.SilkS")
		)
		(fp_line
			(start 0.7874 0.4064)
			(end -0.7874 0.4064)
			(stroke
				(width 0.1524)
				(type default)
			)
			(layer "F.SilkS")
		)
		(fp_line
			(start -0.7874 -0.4064)
			(end 0.7874 -0.4064)
			(stroke
				(width 0.1524)
				(type default)
			)
			(layer "F.SilkS")
		)
		(fp_line
			(start 0.7874 -0.4064)
			(end 0.7874 0.4064)
			(stroke
				(width 0.1524)
				(type default)
			)
			(layer "F.SilkS")
		)
		(fp_line
			(start -0.67945 0.3048)
			(end -0.67945 -0.305054)
			(stroke
				(width 0.1)
				(type default)
			)
			(layer "F.Fab")
		)
		(fp_line
			(start -0.12065 0.3048)
			(end -0.67945 0.3048)
			(stroke
				(width 0.1)
				(type default)
			)
			(layer "F.Fab")
		)
		(fp_line
			(start 0.120396 0.3048)
			(end 0.120396 0.2794)
			(stroke
				(width 0.1)
				(type default)
			)
			(layer "F.Fab")
		)
		(fp_line
			(start 0.67945 0.3048)
			(end 0.120396 0.3048)
			(stroke
				(width 0.1)
				(type default)
			)
			(layer "F.Fab")
		)
		(fp_line
			(start -0.12065 0.2794)
			(end -0.12065 0.3048)
			(stroke
				(width 0.1)
				(type default)
			)
			(layer "F.Fab")
		)
		(fp_line
			(start 0.120396 0.2794)
			(end -0.12065 0.2794)
			(stroke
				(width 0.1)
				(type default)
			)
			(layer "F.Fab")
		)
		(fp_line
			(start -0.12065 -0.2794)
			(end 0.12065 -0.2794)
			(stroke
				(width 0.1)
				(type default)
			)
			(layer "F.Fab")
		)
		(fp_line
			(start 0.12065 -0.2794)
			(end 0.12065 -0.3048)
			(stroke
				(width 0.1)
				(type default)
			)
			(layer "F.Fab")
		)
		(fp_line
			(start 0.12065 -0.3048)
			(end 0.67945 -0.3048)
			(stroke
				(width 0.1)
				(type default)
			)
			(layer "F.Fab")
		)
		(fp_line
			(start 0.67945 -0.3048)
			(end 0.67945 0.3048)
			(stroke
				(width 0.1)
				(type default)
			)
			(layer "F.Fab")
		)
		(fp_line
			(start -0.67945 -0.305054)
			(end -0.12065 -0.305054)
			(stroke
				(width 0.1)
				(type default)
			)
			(layer "F.Fab")
		)
		(fp_line
			(start -0.12065 -0.305054)
			(end -0.12065 -0.2794)
			(stroke
				(width 0.1)
				(type default)
			)
			(layer "F.Fab")
		)
		(pad "1" smd circle
			(at -0.40005 0 270)
			(size 0 0)
			(layers "F.Cu" "F.Mask" "F.Paste")
			(net "PEX0_MODE_SEL12")
		)
		(pad "2" smd circle
			(at 0.40005 0 270)
			(size 0 0)
			(layers "F.Cu" "F.Mask" "F.Paste")
			(net "P1V8_PEX")
		)
	)
	(footprint ""
		(layer "F.Cu")
		(at 333.045816 -46.4439 180)
		(property "Reference" "U74"
			(at 0.356616 -2.40157 0)
			(unlocked yes)
			(layer "F.SilkS")
			(effects
				(font
					(size 0.7874 0.5842)
					(thickness 0.1524)
				)
			)
		)
		(property "Value" ""
			(at 0 0 180)
			(layer "F.Fab")
			(effects
				(font
					(size 1.27 1.27)
				)
			)
		)
		(duplicate_pad_numbers_are_jumpers no)
		(fp_line
			(start 1.500124 1.500124)
			(end 1.004062 1.500124)
			(stroke
				(width 0.1524)
				(type default)
			)
			(layer "F.SilkS")
		)
		(fp_line
			(start 1.500124 1.004062)
			(end 1.500124 1.500124)
			(stroke
				(width 0.1524)
				(type default)
			)
			(layer "F.SilkS")
		)
		(fp_line
			(start 1.500124 -1.500124)
			(end 1.500124 -1.004062)
			(stroke
				(width 0.1524)
				(type default)
			)
			(layer "F.SilkS")
		)
		(fp_line
			(start 1.004062 -1.500124)
			(end 1.500124 -1.500124)
			(stroke
				(width 0.1524)
				(type default)
			)
			(layer "F.SilkS")
		)
		(fp_line
			(start -1.004062 1.500124)
			(end -1.500124 1.500124)
			(stroke
				(width 0.1524)
				(type default)
			)
			(layer "F.SilkS")
		)
		(fp_line
			(start -1.500124 1.500124)
			(end -1.500124 1.004062)
			(stroke
				(width 0.1524)
				(type default)
			)
			(layer "F.SilkS")
		)
		(fp_line
			(start -1.500124 -1.004062)
			(end -1.500124 -1.500124)
			(stroke
				(width 0.1524)
				(type default)
			)
			(layer "F.SilkS")
		)
		(fp_line
			(start -1.500124 -1.500124)
			(end -1.004062 -1.500124)
			(stroke
				(width 0.1524)
				(type default)
			)
			(layer "F.SilkS")
		)
		(fp_poly
			(pts
				(xy -1.926844 -2.242058) (xy -2.645156 -1.523492) (xy -1.567688 -1.164336)
			)
			(stroke
				(width 0)
				(type default)
			)
			(fill yes)
			(layer "F.SilkS")
		)
		(fp_line
			(start 1.500124 1.500124)
			(end -1.500124 1.500124)
			(stroke
				(width 0.1)
				(type default)
			)
			(layer "F.Fab")
		)
		(fp_line
			(start 1.500124 -1.500124)
			(end 1.500124 1.500124)
			(stroke
				(width 0.1)
				(type default)
			)
			(layer "F.Fab")
		)
		(fp_line
			(start -1.500124 1.500124)
			(end -1.500124 -1.500124)
			(stroke
				(width 0.1)
				(type default)
			)
			(layer "F.Fab")
		)
		(fp_line
			(start -1.500124 -1.500124)
			(end 1.500124 -1.500124)
			(stroke
				(width 0.1)
				(type default)
			)
			(layer "F.Fab")
		)
		(fp_poly
			(pts
				(xy -2.847848 -1.258062) (xy -2.847848 -0.242062) (xy -1.831848 -0.750062)
			)
			(stroke
				(width 0)
				(type default)
			)
			(fill yes)
			(layer "F.Fab")
		)
		(pad "1" smd rect
			(at -1.400048 -0.750062 90)
			(size 0.2286 0.6096)
			(layers "F.Cu" "F.Mask" "F.Paste")
			(net "SSD11_ADC_A1")
		)
		(pad "2" smd rect
			(at -1.400048 -0.249936 90)
			(size 0.2286 0.6096)
			(layers "F.Cu" "F.Mask" "F.Paste")
			(net "SSD11_ADC_A0")
		)
		(pad "3" smd rect
			(at -1.400048 0.249936 90)
			(size 0.2286 0.6096)
			(layers "F.Cu" "F.Mask" "F.Paste")
			(net "SSD11_ADC_ALERT_N")
		)
		(pad "4" smd rect
			(at -1.400048 0.750062 90)
			(size 0.2286 0.6096)
			(layers "F.Cu" "F.Mask" "F.Paste")
			(net "SMB_SSD11_ADC_SDA")
		)
		(pad "5" smd rect
			(at -0.750062 1.400048 180)
			(size 0.2286 0.6096)
			(layers "F.Cu" "F.Mask" "F.Paste")
			(net "SMB_SSD11_ADC_SCL")
		)
		(pad "6" smd rect
			(at -0.249936 1.400048 180)
			(size 0.2286 0.6096)
			(layers "F.Cu" "F.Mask" "F.Paste")
			(net "Net_8696")
		)
		(pad "7" smd rect
			(at 0.249936 1.400048 180)
			(size 0.2286 0.6096)
			(layers "F.Cu" "F.Mask" "F.Paste")
			(net "Net_8695")
		)
		(pad "8" smd rect
			(at 0.750062 1.400048 180)
			(size 0.2286 0.6096)
			(layers "F.Cu" "F.Mask" "F.Paste")
			(net "Net_8694")
		)
		(pad "9" smd rect
			(at 1.400048 0.750062 90)
			(size 0.2286 0.6096)
			(layers "F.Cu" "F.Mask" "F.Paste")
			(net "P3V3_AUX")
		)
		(pad "10" smd rect
			(at 1.400048 0.249936 90)
			(size 0.2286 0.6096)
			(layers "F.Cu" "F.Mask" "F.Paste")
			(net "GND")
		)
		(pad "11" smd rect
			(at 1.400048 -0.249936 90)
			(size 0.2286 0.6096)
			(layers "F.Cu" "F.Mask" "F.Paste")
			(net "P12V_SSD11_R")
		)
		(pad "12" smd rect
			(at 1.400048 -0.750062 90)
			(size 0.2286 0.6096)
			(layers "F.Cu" "F.Mask" "F.Paste")
			(net "P12V_SSD11_VIN_N")
		)
		(pad "13" smd rect
			(at 0.750062 -1.400048 180)
			(size 0.2286 0.6096)
			(layers "F.Cu" "F.Mask" "F.Paste")
			(net "P12V_SSD11_VIN_P")
		)
		(pad "14" smd rect
			(at 0.249936 -1.400048 180)
			(size 0.2286 0.6096)
			(layers "F.Cu" "F.Mask" "F.Paste")
			(net "Net_8693")
		)
		(pad "15" smd rect
			(at -0.249936 -1.400048 180)
			(size 0.2286 0.6096)
			(layers "F.Cu" "F.Mask" "F.Paste")
			(net "Net_8692")
		)
		(pad "16" smd rect
			(at -0.750062 -1.400048 180)
			(size 0.2286 0.6096)
			(layers "F.Cu" "F.Mask" "F.Paste")
			(net "Net_8691")
		)
		(pad "TH" smd rect
			(at 0 0 180)
			(size 1.7018 1.7018)
			(layers "F.Cu" "F.Mask" "F.Paste")
			(net "GND")
		)
		(zone
			(layer "F.Cu")
			(hatch none 0.5)
			(connect_pads
				(clearance 0)
			)
			(min_thickness 0.25)
			(keepout
				(tracks not_allowed)
				(vias allowed)
				(pads allowed)
				(copperpour not_allowed)
				(footprints allowed)
			)
			(placement
				(enabled no)
				(sheetname "")
			)
			(fill
				(thermal_gap 0.5)
				(thermal_bridge_width 0.5)
				(island_removal_mode 0)
			)
			(polygon
				(pts
					(xy 334.090264 -46.4185) (xy 334.090264 -45.399452) (xy 332.001368 -45.399452) (xy 332.001368 -47.488348)
					(xy 334.090264 -47.488348) (xy 334.090264 -46.4439) (xy 333.947516 -46.4439) (xy 333.947516 -47.3456)
					(xy 332.144116 -47.3456) (xy 332.144116 -45.5422) (xy 333.947516 -45.5422) (xy 333.947516 -46.4185)
				)
			)
		)
	)
	(footprint ""
		(layer "F.Cu")
		(at 143.490442 -252.356874 -90)
		(property "Reference" "R1294"
			(at 0 0 270)
			(layer "F.SilkS")
			(hide yes)
			(effects
				(font
					(size 1.27 1.27)
				)
			)
		)
		(property "Value" ""
			(at 0 0 270)
			(layer "F.Fab")
			(effects
				(font
					(size 1.27 1.27)
				)
			)
		)
		(duplicate_pad_numbers_are_jumpers no)
		(fp_line
			(start -0.7874 0.4064)
			(end -0.7874 -0.4064)
			(stroke
				(width 0.1524)
				(type default)
			)
			(layer "F.SilkS")
		)
		(fp_line
			(start 0.7874 0.4064)
			(end -0.7874 0.4064)
			(stroke
				(width 0.1524)
				(type default)
			)
			(layer "F.SilkS")
		)
		(fp_line
			(start -0.7874 -0.4064)
			(end 0.7874 -0.4064)
			(stroke
				(width 0.1524)
				(type default)
			)
			(layer "F.SilkS")
		)
		(fp_line
			(start 0.7874 -0.4064)
			(end 0.7874 0.4064)
			(stroke
				(width 0.1524)
				(type default)
			)
			(layer "F.SilkS")
		)
		(fp_line
			(start -0.67945 0.3048)
			(end -0.67945 -0.305054)
			(stroke
				(width 0.1)
				(type default)
			)
			(layer "F.Fab")
		)
		(fp_line
			(start -0.12065 0.3048)
			(end -0.67945 0.3048)
			(stroke
				(width 0.1)
				(type default)
			)
			(layer "F.Fab")
		)
		(fp_line
			(start 0.120396 0.3048)
			(end 0.120396 0.2794)
			(stroke
				(width 0.1)
				(type default)
			)
			(layer "F.Fab")
		)
		(fp_line
			(start 0.67945 0.3048)
			(end 0.120396 0.3048)
			(stroke
				(width 0.1)
				(type default)
			)
			(layer "F.Fab")
		)
		(fp_line
			(start -0.12065 0.2794)
			(end -0.12065 0.3048)
			(stroke
				(width 0.1)
				(type default)
			)
			(layer "F.Fab")
		)
		(fp_line
			(start 0.120396 0.2794)
			(end -0.12065 0.2794)
			(stroke
				(width 0.1)
				(type default)
			)
			(layer "F.Fab")
		)
		(fp_line
			(start -0.12065 -0.2794)
			(end 0.12065 -0.2794)
			(stroke
				(width 0.1)
				(type default)
			)
			(layer "F.Fab")
		)
		(fp_line
			(start 0.12065 -0.2794)
			(end 0.12065 -0.3048)
			(stroke
				(width 0.1)
				(type default)
			)
			(layer "F.Fab")
		)
		(fp_line
			(start 0.12065 -0.3048)
			(end 0.67945 -0.3048)
			(stroke
				(width 0.1)
				(type default)
			)
			(layer "F.Fab")
		)
		(fp_line
			(start 0.67945 -0.3048)
			(end 0.67945 0.3048)
			(stroke
				(width 0.1)
				(type default)
			)
			(layer "F.Fab")
		)
		(fp_line
			(start -0.67945 -0.305054)
			(end -0.12065 -0.305054)
			(stroke
				(width 0.1)
				(type default)
			)
			(layer "F.Fab")
		)
		(fp_line
			(start -0.12065 -0.305054)
			(end -0.12065 -0.2794)
			(stroke
				(width 0.1)
				(type default)
			)
			(layer "F.Fab")
		)
		(pad "1" smd circle
			(at -0.40005 0 270)
			(size 0 0)
			(layers "F.Cu" "F.Mask" "F.Paste")
			(net "GND")
		)
		(pad "2" smd circle
			(at 0.40005 0 270)
			(size 0 0)
			(layers "F.Cu" "F.Mask" "F.Paste")
			(net "PEX1_MODE_SEL5")
		)
	)
	(footprint ""
		(layer "F.Cu")
		(at 426.567854 -51.019456)
		(property "Reference" "PC435"
			(at 0 0 0)
			(layer "F.SilkS")
			(hide yes)
			(effects
				(font
					(size 1.27 1.27)
				)
			)
		)
		(property "Value" ""
			(at 0 0 0)
			(layer "F.Fab")
			(effects
				(font
					(size 1.27 1.27)
				)
			)
		)
		(duplicate_pad_numbers_are_jumpers no)
		(fp_line
			(start -0.7874 -0.4064)
			(end 0.7874 -0.4064)
			(stroke
				(width 0.1524)
				(type default)
			)
			(layer "F.SilkS")
		)
		(fp_line
			(start -0.7874 0.4064)
			(end -0.7874 -0.4064)
			(stroke
				(width 0.1524)
				(type default)
			)
			(layer "F.SilkS")
		)
		(fp_line
			(start 0.7874 -0.4064)
			(end 0.7874 0.4064)
			(stroke
				(width 0.1524)
				(type default)
			)
			(layer "F.SilkS")
		)
		(fp_line
			(start 0.7874 0.4064)
			(end -0.7874 0.4064)
			(stroke
				(width 0.1524)
				(type default)
			)
			(layer "F.SilkS")
		)
		(fp_line
			(start -0.67945 -0.305054)
			(end -0.12065 -0.305054)
			(stroke
				(width 0.1)
				(type default)
			)
			(layer "F.Fab")
		)
		(fp_line
			(start -0.67945 0.3048)
			(end -0.67945 -0.305054)
			(stroke
				(width 0.1)
				(type default)
			)
			(layer "F.Fab")
		)
		(fp_line
			(start -0.12065 -0.305054)
			(end -0.12065 -0.2794)
			(stroke
				(width 0.1)
				(type default)
			)
			(layer "F.Fab")
		)
		(fp_line
			(start -0.12065 -0.2794)
			(end 0.12065 -0.2794)
			(stroke
				(width 0.1)
				(type default)
			)
			(layer "F.Fab")
		)
		(fp_line
			(start -0.12065 0.2794)
			(end -0.12065 0.3048)
			(stroke
				(width 0.1)
				(type default)
			)
			(layer "F.Fab")
		)
		(fp_line
			(start -0.12065 0.3048)
			(end -0.67945 0.3048)
			(stroke
				(width 0.1)
				(type default)
			)
			(layer "F.Fab")
		)
		(fp_line
			(start 0.120396 0.2794)
			(end -0.12065 0.2794)
			(stroke
				(width 0.1)
				(type default)
			)
			(layer "F.Fab")
		)
		(fp_line
			(start 0.120396 0.3048)
			(end 0.120396 0.2794)
			(stroke
				(width 0.1)
				(type default)
			)
			(layer "F.Fab")
		)
		(fp_line
			(start 0.12065 -0.3048)
			(end 0.67945 -0.3048)
			(stroke
				(width 0.1)
				(type default)
			)
			(layer "F.Fab")
		)
		(fp_line
			(start 0.12065 -0.2794)
			(end 0.12065 -0.3048)
			(stroke
				(width 0.1)
				(type default)
			)
			(layer "F.Fab")
		)
		(fp_line
			(start 0.67945 -0.3048)
			(end 0.67945 0.3048)
			(stroke
				(width 0.1)
				(type default)
			)
			(layer "F.Fab")
		)
		(fp_line
			(start 0.67945 0.3048)
			(end 0.120396 0.3048)
			(stroke
				(width 0.1)
				(type default)
			)
			(layer "F.Fab")
		)
		(pad "1" smd circle
			(at -0.40005 0)
			(size 0 0)
			(layers "F.Cu" "F.Mask" "F.Paste")
			(net "P12V_SSD14_SS")
		)
		(pad "2" smd circle
			(at 0.40005 0)
			(size 0 0)
			(layers "F.Cu" "F.Mask" "F.Paste")
			(net "GND")
		)
	)
	(footprint ""
		(layer "F.Cu")
		(at 2.040128 -395.448282 180)
		(property "Reference" "R6740"
			(at 0 0 180)
			(layer "F.SilkS")
			(hide yes)
			(effects
				(font
					(size 1.27 1.27)
				)
			)
		)
		(property "Value" ""
			(at 0 0 180)
			(layer "F.Fab")
			(effects
				(font
					(size 1.27 1.27)
				)
			)
		)
		(duplicate_pad_numbers_are_jumpers no)
		(fp_line
			(start 0.7874 0.4064)
			(end -0.7874 0.4064)
			(stroke
				(width 0.1524)
				(type default)
			)
			(layer "F.SilkS")
		)
		(fp_line
			(start 0.7874 -0.4064)
			(end 0.7874 0.4064)
			(stroke
				(width 0.1524)
				(type default)
			)
			(layer "F.SilkS")
		)
		(fp_line
			(start -0.7874 0.4064)
			(end -0.7874 -0.4064)
			(stroke
				(width 0.1524)
				(type default)
			)
			(layer "F.SilkS")
		)
		(fp_line
			(start -0.7874 -0.4064)
			(end 0.7874 -0.4064)
			(stroke
				(width 0.1524)
				(type default)
			)
			(layer "F.SilkS")
		)
		(fp_line
			(start 0.67945 0.3048)
			(end 0.120396 0.3048)
			(stroke
				(width 0.1)
				(type default)
			)
			(layer "F.Fab")
		)
		(fp_line
			(start 0.67945 -0.3048)
			(end 0.67945 0.3048)
			(stroke
				(width 0.1)
				(type default)
			)
			(layer "F.Fab")
		)
		(fp_line
			(start 0.12065 -0.2794)
			(end 0.12065 -0.3048)
			(stroke
				(width 0.1)
				(type default)
			)
			(layer "F.Fab")
		)
		(fp_line
			(start 0.12065 -0.3048)
			(end 0.67945 -0.3048)
			(stroke
				(width 0.1)
				(type default)
			)
			(layer "F.Fab")
		)
		(fp_line
			(start 0.120396 0.3048)
			(end 0.120396 0.2794)
			(stroke
				(width 0.1)
				(type default)
			)
			(layer "F.Fab")
		)
		(fp_line
			(start 0.120396 0.2794)
			(end -0.12065 0.2794)
			(stroke
				(width 0.1)
				(type default)
			)
			(layer "F.Fab")
		)
		(fp_line
			(start -0.12065 0.3048)
			(end -0.67945 0.3048)
			(stroke
				(width 0.1)
				(type default)
			)
			(layer "F.Fab")
		)
		(fp_line
			(start -0.12065 0.2794)
			(end -0.12065 0.3048)
			(stroke
				(width 0.1)
				(type default)
			)
			(layer "F.Fab")
		)
		(fp_line
			(start -0.12065 -0.2794)
			(end 0.12065 -0.2794)
			(stroke
				(width 0.1)
				(type default)
			)
			(layer "F.Fab")
		)
		(fp_line
			(start -0.12065 -0.305054)
			(end -0.12065 -0.2794)
			(stroke
				(width 0.1)
				(type default)
			)
			(layer "F.Fab")
		)
		(fp_line
			(start -0.67945 0.3048)
			(end -0.67945 -0.305054)
			(stroke
				(width 0.1)
				(type default)
			)
			(layer "F.Fab")
		)
		(fp_line
			(start -0.67945 -0.305054)
			(end -0.12065 -0.305054)
			(stroke
				(width 0.1)
				(type default)
			)
			(layer "F.Fab")
		)
		(pad "1" smd circle
			(at -0.40005 0 180)
			(size 0 0)
			(layers "F.Cu" "F.Mask" "F.Paste")
			(net "P3V3_USB_8042")
		)
		(pad "2" smd circle
			(at 0.40005 0 180)
			(size 0 0)
			(layers "F.Cu" "F.Mask" "F.Paste")
			(net "BIC_USB_8042_HUB_OVCUR1")
		)
	)
	(footprint ""
		(layer "F.Cu")
		(at 413.293052 -356.244906 90)
		(property "Reference" "C2444"
			(at 0 0 90)
			(layer "F.SilkS")
			(hide yes)
			(effects
				(font
					(size 1.27 1.27)
				)
			)
		)
		(property "Value" ""
			(at 0 0 90)
			(layer "F.Fab")
			(effects
				(font
					(size 1.27 1.27)
				)
			)
		)
		(duplicate_pad_numbers_are_jumpers no)
		(fp_line
			(start 0.299974 -0.150114)
			(end 0.299974 0.150114)
			(stroke
				(width 0.1)
				(type default)
			)
			(layer "F.Fab")
		)
		(fp_line
			(start -0.299974 -0.150114)
			(end 0.299974 -0.150114)
			(stroke
				(width 0.1)
				(type default)
			)
			(layer "F.Fab")
		)
		(fp_line
			(start 0.299974 0.150114)
			(end -0.299974 0.150114)
			(stroke
				(width 0.1)
				(type default)
			)
			(layer "F.Fab")
		)
		(fp_line
			(start -0.299974 0.150114)
			(end -0.299974 -0.150114)
			(stroke
				(width 0.1)
				(type default)
			)
			(layer "F.Fab")
		)
		(pad "1" smd rect
			(at -0.2667 0 90)
			(size 0.3048 0.381)
			(layers "F.Cu" "F.Mask" "F.Paste")
			(net "P5E_PEX3_STN4_TX_DN<77>")
		)
		(pad "2" smd rect
			(at 0.2667 0 90)
			(size 0.3048 0.381)
			(layers "F.Cu" "F.Mask" "F.Paste")
			(net "P5E_PEX3_STN4_TX_C_DN<77>")
		)
	)
)
